# T6G (Grand Teton) — schematic netlist excerpt (pin names and nets, part order shuffled) for the footprints in the layout excerpt that follows; sources: Cadence DE-HDL packaged netlist, KiCad conversion of 04192023_DAF0TMB3IC0_F0TG_MB_C_brd_V02_OCP.brd

PC148_6  Q_CAP  22UF 4V 20% X6S  pkg C0805  page 220 : A = PVDDCR_CPU1_P1 ; B = GND
R3111  Q_RES  0 5% CHIP  pkg 0402LF  page 248 : A = I3C_BMC_SWB_SDA ; B = I3C_BMC_SWB_R_SDA
R8422  Q_RES  10K 1% CHIP  pkg 0402LF  page 131 : A = SGPIO_OCP_SFF_DATAOUT ; B = GND

(kicad_pcb
	(version 20260206)
	(generator "pcbnew")
	(generator_version "10.0")
	(general
		(thickness 1.6)
		(legacy_teardrops no)
	)
	(paper "A4")
	(title_block
		(title "04192023_DAF0TMB3IC0_F0TG_MB_C_brd_V02_OCP.brd")
		(comment 1 "Grand Teton / footprints 5212-5214 of 8354")
	)
	(layers
		(0 "F.Cu" signal "TOP")
		(4 "In1.Cu" signal "GND")
		(6 "In2.Cu" signal "IN1")
		(8 "In3.Cu" signal "GND1")
		(10 "In4.Cu" signal "IN2")
		(12 "In5.Cu" signal "GND2")
		(14 "In6.Cu" signal "IN3")
		(16 "In7.Cu" signal "GND3")
		(18 "In8.Cu" signal "VCC")
		(20 "In9.Cu" signal "VCC1")
		(22 "In10.Cu" signal "GND4")
		(24 "In11.Cu" signal "IN4")
		(26 "In12.Cu" signal "GND5")
		(28 "In13.Cu" signal "IN5")
		(30 "In14.Cu" signal "GND6")
		(32 "In15.Cu" signal "IN6")
		(34 "In16.Cu" signal "GND7")
		(2 "B.Cu" signal "BOTTOM")
		(9 "F.Adhes" user "F.Adhesive")
		(11 "B.Adhes" user "B.Adhesive")
		(13 "F.Paste" user "Package Geometry/Pastemask Top")
		(15 "B.Paste" user "Package Geometry/Pastemask Bottom")
		(5 "F.SilkS" user "Ref Des/Silkscreen Top")
		(7 "B.SilkS" user "Ref Des/Silkscreen Bottom")
		(1 "F.Mask" user "Board Geometry/Soldermask Top")
		(3 "B.Mask" user "Board Geometry/Soldermask Bottom")
		(17 "Dwgs.User" user "User.Drawings")
		(19 "Cmts.User" user "User.Comments")
		(21 "Eco1.User" user "User.Eco1")
		(23 "Eco2.User" user "User.Eco2")
		(25 "Edge.Cuts" user "Board Geometry/Outline")
		(27 "Margin" user)
		(31 "F.CrtYd" user "Package Geometry/Place Bound Top")
		(29 "B.CrtYd" user "Package Geometry/Place Bound Bottom")
		(35 "F.Fab" user "Ref Des/Assembly Top")
		(33 "B.Fab" user "Ref Des/Assembly Bottom")
	)
	(footprint ""
		(layer "B.Cu")
		(at 450.482716 -10.594086 90)
		(property "Reference" "R8422"
			(at 0 0 90)
			(layer "B.SilkS")
			(hide yes)
			(effects
				(font
					(size 1.27 1.27)
				)
				(justify mirror)
			)
		)
		(property "Value" ""
			(at 0 0 90)
			(layer "B.Fab")
			(effects
				(font
					(size 1.27 1.27)
				)
				(justify mirror)
			)
		)
		(duplicate_pad_numbers_are_jumpers no)
		(fp_line
			(start 0.7874 -0.4064)
			(end -0.7874 -0.4064)
			(stroke
				(width 0.1524)
				(type default)
			)
			(layer "B.SilkS")
		)
		(fp_line
			(start -0.7874 -0.4064)
			(end -0.7874 0.4064)
			(stroke
				(width 0.1524)
				(type default)
			)
			(layer "B.SilkS")
		)
		(fp_line
			(start 0.7874 0.4064)
			(end 0.7874 -0.4064)
			(stroke
				(width 0.1524)
				(type default)
			)
			(layer "B.SilkS")
		)
		(fp_line
			(start -0.7874 0.4064)
			(end 0.7874 0.4064)
			(stroke
				(width 0.1524)
				(type default)
			)
			(layer "B.SilkS")
		)
		(fp_line
			(start 0.67945 -0.305054)
			(end 0.12065 -0.305054)
			(stroke
				(width 0.1)
				(type default)
			)
			(layer "B.Fab")
		)
		(fp_line
			(start 0.12065 -0.305054)
			(end 0.12065 -0.2794)
			(stroke
				(width 0.1)
				(type default)
			)
			(layer "B.Fab")
		)
		(fp_line
			(start -0.12065 -0.3048)
			(end -0.67945 -0.3048)
			(stroke
				(width 0.1)
				(type default)
			)
			(layer "B.Fab")
		)
		(fp_line
			(start -0.67945 -0.3048)
			(end -0.67945 0.3048)
			(stroke
				(width 0.1)
				(type default)
			)
			(layer "B.Fab")
		)
		(fp_line
			(start 0.12065 -0.2794)
			(end -0.12065 -0.2794)
			(stroke
				(width 0.1)
				(type default)
			)
			(layer "B.Fab")
		)
		(fp_line
			(start -0.12065 -0.2794)
			(end -0.12065 -0.3048)
			(stroke
				(width 0.1)
				(type default)
			)
			(layer "B.Fab")
		)
		(fp_line
			(start 0.12065 0.2794)
			(end 0.12065 0.3048)
			(stroke
				(width 0.1)
				(type default)
			)
			(layer "B.Fab")
		)
		(fp_line
			(start -0.120396 0.2794)
			(end 0.12065 0.2794)
			(stroke
				(width 0.1)
				(type default)
			)
			(layer "B.Fab")
		)
		(fp_line
			(start 0.67945 0.3048)
			(end 0.67945 -0.305054)
			(stroke
				(width 0.1)
				(type default)
			)
			(layer "B.Fab")
		)
		(fp_line
			(start 0.12065 0.3048)
			(end 0.67945 0.3048)
			(stroke
				(width 0.1)
				(type default)
			)
			(layer "B.Fab")
		)
		(fp_line
			(start -0.120396 0.3048)
			(end -0.120396 0.2794)
			(stroke
				(width 0.1)
				(type default)
			)
			(layer "B.Fab")
		)
		(fp_line
			(start -0.67945 0.3048)
			(end -0.120396 0.3048)
			(stroke
				(width 0.1)
				(type default)
			)
			(layer "B.Fab")
		)
		(pad "1" smd circle
			(at 0.40005 0 270)
			(size 0 0)
			(layers "B.Cu" "B.Mask" "B.Paste")
			(net "SGPIO_OCP_SFF_DATAOUT")
		)
		(pad "2" smd circle
			(at -0.40005 0 270)
			(size 0 0)
			(layers "B.Cu" "B.Mask" "B.Paste")
			(net "GND")
		)
	)
	(footprint ""
		(layer "B.Cu")
		(at 107.790742 -331.309472 -90)
		(property "Reference" "PC148_6"
			(at 0 0 90)
			(layer "B.SilkS")
			(hide yes)
			(effects
				(font
					(size 1.27 1.27)
				)
				(justify mirror)
			)
		)
		(property "Value" ""
			(at 0 0 90)
			(layer "B.Fab")
			(effects
				(font
					(size 1.27 1.27)
				)
				(justify mirror)
			)
		)
		(duplicate_pad_numbers_are_jumpers no)
		(fp_line
			(start -1.524 0.762)
			(end 1.524 0.762)
			(stroke
				(width 0.1524)
				(type default)
			)
			(layer "B.SilkS")
		)
		(fp_line
			(start 1.524 0.762)
			(end 1.524 -0.762)
			(stroke
				(width 0.1524)
				(type default)
			)
			(layer "B.SilkS")
		)
		(fp_line
			(start -1.524 -0.762)
			(end -1.524 0.762)
			(stroke
				(width 0.1524)
				(type default)
			)
			(layer "B.SilkS")
		)
		(fp_line
			(start 1.524 -0.762)
			(end -1.524 -0.762)
			(stroke
				(width 0.1524)
				(type default)
			)
			(layer "B.SilkS")
		)
		(fp_line
			(start -1.1049 0.724916)
			(end -1.1049 -0.724916)
			(stroke
				(width 0.1)
				(type default)
			)
			(layer "B.Fab")
		)
		(fp_line
			(start 1.1049 0.724916)
			(end -1.1049 0.724916)
			(stroke
				(width 0.1)
				(type default)
			)
			(layer "B.Fab")
		)
		(fp_line
			(start -1.1049 -0.724916)
			(end 1.1049 -0.724916)
			(stroke
				(width 0.1)
				(type default)
			)
			(layer "B.Fab")
		)
		(fp_line
			(start 1.1049 -0.724916)
			(end 1.1049 0.724916)
			(stroke
				(width 0.1)
				(type default)
			)
			(layer "B.Fab")
		)
		(pad "1" smd rect
			(at 0.889 0 270)
			(size 1.016 1.27)
			(layers "B.Cu" "B.Mask" "B.Paste")
			(net "PVDDCR_CPU1_P1")
		)
		(pad "2" smd rect
			(at -0.889 0 270)
			(size 1.016 1.27)
			(layers "B.Cu" "B.Mask" "B.Paste")
			(net "GND")
		)
	)
	(footprint ""
		(layer "B.Cu")
		(at 290.092384 -425.179998 180)
		(property "Reference" "R3111"
			(at 0 0 0)
			(layer "B.SilkS")
			(hide yes)
			(effects
				(font
					(size 1.27 1.27)
				)
				(justify mirror)
			)
		)
		(property "Value" ""
			(at 0 0 0)
			(layer "B.Fab")
			(effects
				(font
					(size 1.27 1.27)
				)
				(justify mirror)
			)
		)
		(duplicate_pad_numbers_are_jumpers no)
		(fp_line
			(start 0.7874 0.4064)
			(end 0.7874 -0.4064)
			(stroke
				(width 0.1524)
				(type default)
			)
			(layer "B.SilkS")
		)
		(fp_line
			(start 0.7874 -0.4064)
			(end -0.7874 -0.4064)
			(stroke
				(width 0.1524)
				(type default)
			)
			(layer "B.SilkS")
		)
		(fp_line
			(start -0.7874 0.4064)
			(end 0.7874 0.4064)
			(stroke
				(width 0.1524)
				(type default)
			)
			(layer "B.SilkS")
		)
		(fp_line
			(start -0.7874 -0.4064)
			(end -0.7874 0.4064)
			(stroke
				(width 0.1524)
				(type default)
			)
			(layer "B.SilkS")
		)
		(fp_line
			(start 0.67945 0.3048)
			(end 0.67945 -0.305054)
			(stroke
				(width 0.1)
				(type default)
			)
			(layer "B.Fab")
		)
		(fp_line
			(start 0.67945 -0.305054)
			(end 0.12065 -0.305054)
			(stroke
				(width 0.1)
				(type default)
			)
			(layer "B.Fab")
		)
		(fp_line
			(start 0.12065 0.3048)
			(end 0.67945 0.3048)
			(stroke
				(width 0.1)
				(type default)
			)
			(layer "B.Fab")
		)
		(fp_line
			(start 0.12065 0.2794)
			(end 0.12065 0.3048)
			(stroke
				(width 0.1)
				(type default)
			)
			(layer "B.Fab")
		)
		(fp_line
			(start 0.12065 -0.2794)
			(end -0.12065 -0.2794)
			(stroke
				(width 0.1)
				(type default)
			)
			(layer "B.Fab")
		)
		(fp_line
			(start 0.12065 -0.305054)
			(end 0.12065 -0.2794)
			(stroke
				(width 0.1)
				(type default)
			)
			(layer "B.Fab")
		)
		(fp_line
			(start -0.120396 0.3048)
			(end -0.120396 0.2794)
			(stroke
				(width 0.1)
				(type default)
			)
			(layer "B.Fab")
		)
		(fp_line
			(start -0.120396 0.2794)
			(end 0.12065 0.2794)
			(stroke
				(width 0.1)
				(type default)
			)
			(layer "B.Fab")
		)
		(fp_line
			(start -0.12065 -0.2794)
			(end -0.12065 -0.3048)
			(stroke
				(width 0.1)
				(type default)
			)
			(layer "B.Fab")
		)
		(fp_line
			(start -0.12065 -0.3048)
			(end -0.67945 -0.3048)
			(stroke
				(width 0.1)
				(type default)
			)
			(layer "B.Fab")
		)
		(fp_line
			(start -0.67945 0.3048)
			(end -0.120396 0.3048)
			(stroke
				(width 0.1)
				(type default)
			)
			(layer "B.Fab")
		)
		(fp_line
			(start -0.67945 -0.3048)
			(end -0.67945 0.3048)
			(stroke
				(width 0.1)
				(type default)
			)
			(layer "B.Fab")
		)
		(pad "1" smd circle
			(at 0.40005 0)
			(size 0 0)
			(layers "B.Cu" "B.Mask" "B.Paste")
			(net "I3C_BMC_SWB_SDA")
		)
		(pad "2" smd circle
			(at -0.40005 0)
			(size 0 0)
			(layers "B.Cu" "B.Mask" "B.Paste")
			(net "I3C_BMC_SWB_R_SDA")
		)
	)
)
